(kicad_pcb
	(version 20260206)
	(generator "pcbnew")
	(generator_version "10.0")
	(general
		(thickness 1.6)
		(legacy_teardrops no)
	)
	(paper "A4")
	(title_block
		(title "01162023_DA0F0TEBIF0_F0T_Expander_BD_F_brd_V02_OCP.brd")
		(comment 1 "Grand Teton / footprints 3406-3412 of 9728")
	)
	(layers
		(0 "F.Cu" signal "TOP")
		(4 "In1.Cu" signal "GND")
		(6 "In2.Cu" signal "VCC")
		(8 "In3.Cu" signal "VCC1")
		(10 "In4.Cu" signal "GND1")
		(12 "In5.Cu" signal "IN1")
		(14 "In6.Cu" signal "GND2")
		(16 "In7.Cu" signal "IN2")
		(18 "In8.Cu" signal "GND3")
		(20 "In9.Cu" signal "IN3")
		(22 "In10.Cu" signal "GND4")
		(24 "In11.Cu" signal "IN4")
		(26 "In12.Cu" signal "GND5")
		(28 "In13.Cu" signal "IN5")
		(30 "In14.Cu" signal "GND6")
		(32 "In15.Cu" signal "IN6")
		(34 "In16.Cu" signal "GND7")
		(2 "B.Cu" signal "BOTTOM")
		(9 "F.Adhes" user "F.Adhesive")
		(11 "B.Adhes" user "B.Adhesive")
		(13 "F.Paste" user "Package Geometry/Pastemask Top")
		(15 "B.Paste" user "Package Geometry/Pastemask Bottom")
		(5 "F.SilkS" user "Ref Des/Silkscreen Top")
		(7 "B.SilkS" user "Ref Des/Silkscreen Bottom")
		(1 "F.Mask" user "Board Geometry/Soldermask Top")
		(3 "B.Mask" user "Board Geometry/Soldermask Bottom")
		(17 "Dwgs.User" user "User.Drawings")
		(19 "Cmts.User" user "User.Comments")
		(21 "Eco1.User" user "User.Eco1")
		(23 "Eco2.User" user "User.Eco2")
		(25 "Edge.Cuts" user "Board Geometry/Outline")
		(27 "Margin" user)
		(31 "F.CrtYd" user "Package Geometry/Place Bound Top")
		(29 "B.CrtYd" user "Package Geometry/Place Bound Bottom")
		(35 "F.Fab" user "Ref Des/Assembly Top")
		(33 "B.Fab" user "Ref Des/Assembly Bottom")
	)
	(footprint ""
		(layer "F.Cu")
		(at 333.883 -234.061 90)
		(property "Reference" "R3521"
			(at 0 0 90)
			(layer "F.SilkS")
			(hide yes)
			(effects
				(font
					(size 1.27 1.27)
				)
			)
		)
		(property "Value" ""
			(at 0 0 90)
			(layer "F.Fab")
			(effects
				(font
					(size 1.27 1.27)
				)
			)
		)
		(duplicate_pad_numbers_are_jumpers no)
		(fp_line
			(start 0.7874 -0.4064)
			(end 0.7874 0.4064)
			(stroke
				(width 0.1524)
				(type default)
			)
			(layer "F.SilkS")
		)
		(fp_line
			(start -0.7874 -0.4064)
			(end 0.7874 -0.4064)
			(stroke
				(width 0.1524)
				(type default)
			)
			(layer "F.SilkS")
		)
		(fp_line
			(start 0.7874 0.4064)
			(end -0.7874 0.4064)
			(stroke
				(width 0.1524)
				(type default)
			)
			(layer "F.SilkS")
		)
		(fp_line
			(start -0.7874 0.4064)
			(end -0.7874 -0.4064)
			(stroke
				(width 0.1524)
				(type default)
			)
			(layer "F.SilkS")
		)
		(fp_line
			(start -0.12065 -0.305054)
			(end -0.12065 -0.2794)
			(stroke
				(width 0.1)
				(type default)
			)
			(layer "F.Fab")
		)
		(fp_line
			(start -0.67945 -0.305054)
			(end -0.12065 -0.305054)
			(stroke
				(width 0.1)
				(type default)
			)
			(layer "F.Fab")
		)
		(fp_line
			(start 0.67945 -0.3048)
			(end 0.67945 0.3048)
			(stroke
				(width 0.1)
				(type default)
			)
			(layer "F.Fab")
		)
		(fp_line
			(start 0.12065 -0.3048)
			(end 0.67945 -0.3048)
			(stroke
				(width 0.1)
				(type default)
			)
			(layer "F.Fab")
		)
		(fp_line
			(start 0.12065 -0.2794)
			(end 0.12065 -0.3048)
			(stroke
				(width 0.1)
				(type default)
			)
			(layer "F.Fab")
		)
		(fp_line
			(start -0.12065 -0.2794)
			(end 0.12065 -0.2794)
			(stroke
				(width 0.1)
				(type default)
			)
			(layer "F.Fab")
		)
		(fp_line
			(start 0.120396 0.2794)
			(end -0.12065 0.2794)
			(stroke
				(width 0.1)
				(type default)
			)
			(layer "F.Fab")
		)
		(fp_line
			(start -0.12065 0.2794)
			(end -0.12065 0.3048)
			(stroke
				(width 0.1)
				(type default)
			)
			(layer "F.Fab")
		)
		(fp_line
			(start 0.67945 0.3048)
			(end 0.120396 0.3048)
			(stroke
				(width 0.1)
				(type default)
			)
			(layer "F.Fab")
		)
		(fp_line
			(start 0.120396 0.3048)
			(end 0.120396 0.2794)
			(stroke
				(width 0.1)
				(type default)
			)
			(layer "F.Fab")
		)
		(fp_line
			(start -0.12065 0.3048)
			(end -0.67945 0.3048)
			(stroke
				(width 0.1)
				(type default)
			)
			(layer "F.Fab")
		)
		(fp_line
			(start -0.67945 0.3048)
			(end -0.67945 -0.305054)
			(stroke
				(width 0.1)
				(type default)
			)
			(layer "F.Fab")
		)
		(pad "1" smd circle
			(at -0.40005 0 90)
			(size 0 0)
			(layers "F.Cu" "F.Mask" "F.Paste")
			(net "SSD2_PWR_EN")
		)
		(pad "2" smd circle
			(at 0.40005 0 90)
			(size 0 0)
			(layers "F.Cu" "F.Mask" "F.Paste")
			(net "SSD2_PWR_EN_R")
		)
	)
	(footprint ""
		(layer "F.Cu")
		(at 61.493908 -165.670484 -90)
		(property "Reference" "R2463"
			(at 0 0 270)
			(layer "F.SilkS")
			(hide yes)
			(effects
				(font
					(size 1.27 1.27)
				)
			)
		)
		(property "Value" ""
			(at 0 0 270)
			(layer "F.Fab")
			(effects
				(font
					(size 1.27 1.27)
				)
			)
		)
		(duplicate_pad_numbers_are_jumpers no)
		(fp_line
			(start -0.7874 0.4064)
			(end -0.7874 -0.4064)
			(stroke
				(width 0.1524)
				(type default)
			)
			(layer "F.SilkS")
		)
		(fp_line
			(start 0.7874 0.4064)
			(end -0.7874 0.4064)
			(stroke
				(width 0.1524)
				(type default)
			)
			(layer "F.SilkS")
		)
		(fp_line
			(start -0.7874 -0.4064)
			(end 0.7874 -0.4064)
			(stroke
				(width 0.1524)
				(type default)
			)
			(layer "F.SilkS")
		)
		(fp_line
			(start 0.7874 -0.4064)
			(end 0.7874 0.4064)
			(stroke
				(width 0.1524)
				(type default)
			)
			(layer "F.SilkS")
		)
		(fp_line
			(start -0.67945 0.3048)
			(end -0.67945 -0.305054)
			(stroke
				(width 0.1)
				(type default)
			)
			(layer "F.Fab")
		)
		(fp_line
			(start -0.12065 0.3048)
			(end -0.67945 0.3048)
			(stroke
				(width 0.1)
				(type default)
			)
			(layer "F.Fab")
		)
		(fp_line
			(start 0.120396 0.3048)
			(end 0.120396 0.2794)
			(stroke
				(width 0.1)
				(type default)
			)
			(layer "F.Fab")
		)
		(fp_line
			(start 0.67945 0.3048)
			(end 0.120396 0.3048)
			(stroke
				(width 0.1)
				(type default)
			)
			(layer "F.Fab")
		)
		(fp_line
			(start -0.12065 0.2794)
			(end -0.12065 0.3048)
			(stroke
				(width 0.1)
				(type default)
			)
			(layer "F.Fab")
		)
		(fp_line
			(start 0.120396 0.2794)
			(end -0.12065 0.2794)
			(stroke
				(width 0.1)
				(type default)
			)
			(layer "F.Fab")
		)
		(fp_line
			(start -0.12065 -0.2794)
			(end 0.12065 -0.2794)
			(stroke
				(width 0.1)
				(type default)
			)
			(layer "F.Fab")
		)
		(fp_line
			(start 0.12065 -0.2794)
			(end 0.12065 -0.3048)
			(stroke
				(width 0.1)
				(type default)
			)
			(layer "F.Fab")
		)
		(fp_line
			(start 0.12065 -0.3048)
			(end 0.67945 -0.3048)
			(stroke
				(width 0.1)
				(type default)
			)
			(layer "F.Fab")
		)
		(fp_line
			(start 0.67945 -0.3048)
			(end 0.67945 0.3048)
			(stroke
				(width 0.1)
				(type default)
			)
			(layer "F.Fab")
		)
		(fp_line
			(start -0.67945 -0.305054)
			(end -0.12065 -0.305054)
			(stroke
				(width 0.1)
				(type default)
			)
			(layer "F.Fab")
		)
		(fp_line
			(start -0.12065 -0.305054)
			(end -0.12065 -0.2794)
			(stroke
				(width 0.1)
				(type default)
			)
			(layer "F.Fab")
		)
		(pad "1" smd circle
			(at -0.40005 0 270)
			(size 0 0)
			(layers "F.Cu" "F.Mask" "F.Paste")
			(net "P3V3_NIC0")
		)
		(pad "2" smd circle
			(at 0.40005 0 270)
			(size 0 0)
			(layers "F.Cu" "F.Mask" "F.Paste")
			(net "NIC0_PWRBRK_N")
		)
	)
	(footprint ""
		(layer "F.Cu")
		(at 144.506442 -250.070874 -90)
		(property "Reference" "R1267"
			(at 0 0 270)
			(layer "F.SilkS")
			(hide yes)
			(effects
				(font
					(size 1.27 1.27)
				)
			)
		)
		(property "Value" ""
			(at 0 0 270)
			(layer "F.Fab")
			(effects
				(font
					(size 1.27 1.27)
				)
			)
		)
		(duplicate_pad_numbers_are_jumpers no)
		(fp_line
			(start -0.7874 0.4064)
			(end -0.7874 -0.4064)
			(stroke
				(width 0.1524)
				(type default)
			)
			(layer "F.SilkS")
		)
		(fp_line
			(start 0.7874 0.4064)
			(end -0.7874 0.4064)
			(stroke
				(width 0.1524)
				(type default)
			)
			(layer "F.SilkS")
		)
		(fp_line
			(start -0.7874 -0.4064)
			(end 0.7874 -0.4064)
			(stroke
				(width 0.1524)
				(type default)
			)
			(layer "F.SilkS")
		)
		(fp_line
			(start 0.7874 -0.4064)
			(end 0.7874 0.4064)
			(stroke
				(width 0.1524)
				(type default)
			)
			(layer "F.SilkS")
		)
		(fp_line
			(start -0.67945 0.3048)
			(end -0.67945 -0.305054)
			(stroke
				(width 0.1)
				(type default)
			)
			(layer "F.Fab")
		)
		(fp_line
			(start -0.12065 0.3048)
			(end -0.67945 0.3048)
			(stroke
				(width 0.1)
				(type default)
			)
			(layer "F.Fab")
		)
		(fp_line
			(start 0.120396 0.3048)
			(end 0.120396 0.2794)
			(stroke
				(width 0.1)
				(type default)
			)
			(layer "F.Fab")
		)
		(fp_line
			(start 0.67945 0.3048)
			(end 0.120396 0.3048)
			(stroke
				(width 0.1)
				(type default)
			)
			(layer "F.Fab")
		)
		(fp_line
			(start -0.12065 0.2794)
			(end -0.12065 0.3048)
			(stroke
				(width 0.1)
				(type default)
			)
			(layer "F.Fab")
		)
		(fp_line
			(start 0.120396 0.2794)
			(end -0.12065 0.2794)
			(stroke
				(width 0.1)
				(type default)
			)
			(layer "F.Fab")
		)
		(fp_line
			(start -0.12065 -0.2794)
			(end 0.12065 -0.2794)
			(stroke
				(width 0.1)
				(type default)
			)
			(layer "F.Fab")
		)
		(fp_line
			(start 0.12065 -0.2794)
			(end 0.12065 -0.3048)
			(stroke
				(width 0.1)
				(type default)
			)
			(layer "F.Fab")
		)
		(fp_line
			(start 0.12065 -0.3048)
			(end 0.67945 -0.3048)
			(stroke
				(width 0.1)
				(type default)
			)
			(layer "F.Fab")
		)
		(fp_line
			(start 0.67945 -0.3048)
			(end 0.67945 0.3048)
			(stroke
				(width 0.1)
				(type default)
			)
			(layer "F.Fab")
		)
		(fp_line
			(start -0.67945 -0.305054)
			(end -0.12065 -0.305054)
			(stroke
				(width 0.1)
				(type default)
			)
			(layer "F.Fab")
		)
		(fp_line
			(start -0.12065 -0.305054)
			(end -0.12065 -0.2794)
			(stroke
				(width 0.1)
				(type default)
			)
			(layer "F.Fab")
		)
		(pad "1" smd circle
			(at -0.40005 0 270)
			(size 0 0)
			(layers "F.Cu" "F.Mask" "F.Paste")
			(net "PEX1_DBG_MODE3")
		)
		(pad "2" smd circle
			(at 0.40005 0 270)
			(size 0 0)
			(layers "F.Cu" "F.Mask" "F.Paste")
			(net "P1V8_PEX")
		)
	)
	(footprint ""
		(layer "F.Cu")
		(at 10.401554 -394.13942 -90)
		(property "Reference" "R6742"
			(at 0 0 270)
			(layer "F.SilkS")
			(hide yes)
			(effects
				(font
					(size 1.27 1.27)
				)
			)
		)
		(property "Value" ""
			(at 0 0 270)
			(layer "F.Fab")
			(effects
				(font
					(size 1.27 1.27)
				)
			)
		)
		(duplicate_pad_numbers_are_jumpers no)
		(fp_line
			(start -0.7874 0.4064)
			(end -0.7874 -0.4064)
			(stroke
				(width 0.1524)
				(type default)
			)
			(layer "F.SilkS")
		)
		(fp_line
			(start 0.7874 0.4064)
			(end -0.7874 0.4064)
			(stroke
				(width 0.1524)
				(type default)
			)
			(layer "F.SilkS")
		)
		(fp_line
			(start -0.7874 -0.4064)
			(end 0.7874 -0.4064)
			(stroke
				(width 0.1524)
				(type default)
			)
			(layer "F.SilkS")
		)
		(fp_line
			(start 0.7874 -0.4064)
			(end 0.7874 0.4064)
			(stroke
				(width 0.1524)
				(type default)
			)
			(layer "F.SilkS")
		)
		(fp_line
			(start -0.67945 0.3048)
			(end -0.67945 -0.305054)
			(stroke
				(width 0.1)
				(type default)
			)
			(layer "F.Fab")
		)
		(fp_line
			(start -0.12065 0.3048)
			(end -0.67945 0.3048)
			(stroke
				(width 0.1)
				(type default)
			)
			(layer "F.Fab")
		)
		(fp_line
			(start 0.120396 0.3048)
			(end 0.120396 0.2794)
			(stroke
				(width 0.1)
				(type default)
			)
			(layer "F.Fab")
		)
		(fp_line
			(start 0.67945 0.3048)
			(end 0.120396 0.3048)
			(stroke
				(width 0.1)
				(type default)
			)
			(layer "F.Fab")
		)
		(fp_line
			(start -0.12065 0.2794)
			(end -0.12065 0.3048)
			(stroke
				(width 0.1)
				(type default)
			)
			(layer "F.Fab")
		)
		(fp_line
			(start 0.120396 0.2794)
			(end -0.12065 0.2794)
			(stroke
				(width 0.1)
				(type default)
			)
			(layer "F.Fab")
		)
		(fp_line
			(start -0.12065 -0.2794)
			(end 0.12065 -0.2794)
			(stroke
				(width 0.1)
				(type default)
			)
			(layer "F.Fab")
		)
		(fp_line
			(start 0.12065 -0.2794)
			(end 0.12065 -0.3048)
			(stroke
				(width 0.1)
				(type default)
			)
			(layer "F.Fab")
		)
		(fp_line
			(start 0.12065 -0.3048)
			(end 0.67945 -0.3048)
			(stroke
				(width 0.1)
				(type default)
			)
			(layer "F.Fab")
		)
		(fp_line
			(start 0.67945 -0.3048)
			(end 0.67945 0.3048)
			(stroke
				(width 0.1)
				(type default)
			)
			(layer "F.Fab")
		)
		(fp_line
			(start -0.67945 -0.305054)
			(end -0.12065 -0.305054)
			(stroke
				(width 0.1)
				(type default)
			)
			(layer "F.Fab")
		)
		(fp_line
			(start -0.12065 -0.305054)
			(end -0.12065 -0.2794)
			(stroke
				(width 0.1)
				(type default)
			)
			(layer "F.Fab")
		)
		(pad "1" smd circle
			(at -0.40005 0 270)
			(size 0 0)
			(layers "F.Cu" "F.Mask" "F.Paste")
			(net "P3V3_USB_8042")
		)
		(pad "2" smd circle
			(at 0.40005 0 270)
			(size 0 0)
			(layers "F.Cu" "F.Mask" "F.Paste")
			(net "BIC_USB_8042_HUB_OVCUR3")
		)
	)
	(footprint ""
		(layer "F.Cu")
		(at 229.954836 -240.946178)
		(property "Reference" "C3988"
			(at 0 0 0)
			(layer "F.SilkS")
			(hide yes)
			(effects
				(font
					(size 1.27 1.27)
				)
			)
		)
		(property "Value" ""
			(at 0 0 0)
			(layer "F.Fab")
			(effects
				(font
					(size 1.27 1.27)
				)
			)
		)
		(duplicate_pad_numbers_are_jumpers no)
		(fp_line
			(start -0.7874 -0.4064)
			(end 0.7874 -0.4064)
			(stroke
				(width 0.1524)
				(type default)
			)
			(layer "F.SilkS")
		)
		(fp_line
			(start -0.7874 0.4064)
			(end -0.7874 -0.4064)
			(stroke
				(width 0.1524)
				(type default)
			)
			(layer "F.SilkS")
		)
		(fp_line
			(start 0.7874 -0.4064)
			(end 0.7874 0.4064)
			(stroke
				(width 0.1524)
				(type default)
			)
			(layer "F.SilkS")
		)
		(fp_line
			(start 0.7874 0.4064)
			(end -0.7874 0.4064)
			(stroke
				(width 0.1524)
				(type default)
			)
			(layer "F.SilkS")
		)
		(fp_line
			(start -0.67945 -0.305054)
			(end -0.12065 -0.305054)
			(stroke
				(width 0.1)
				(type default)
			)
			(layer "F.Fab")
		)
		(fp_line
			(start -0.67945 0.3048)
			(end -0.67945 -0.305054)
			(stroke
				(width 0.1)
				(type default)
			)
			(layer "F.Fab")
		)
		(fp_line
			(start -0.12065 -0.305054)
			(end -0.12065 -0.2794)
			(stroke
				(width 0.1)
				(type default)
			)
			(layer "F.Fab")
		)
		(fp_line
			(start -0.12065 -0.2794)
			(end 0.12065 -0.2794)
			(stroke
				(width 0.1)
				(type default)
			)
			(layer "F.Fab")
		)
		(fp_line
			(start -0.12065 0.2794)
			(end -0.12065 0.3048)
			(stroke
				(width 0.1)
				(type default)
			)
			(layer "F.Fab")
		)
		(fp_line
			(start -0.12065 0.3048)
			(end -0.67945 0.3048)
			(stroke
				(width 0.1)
				(type default)
			)
			(layer "F.Fab")
		)
		(fp_line
			(start 0.120396 0.2794)
			(end -0.12065 0.2794)
			(stroke
				(width 0.1)
				(type default)
			)
			(layer "F.Fab")
		)
		(fp_line
			(start 0.120396 0.3048)
			(end 0.120396 0.2794)
			(stroke
				(width 0.1)
				(type default)
			)
			(layer "F.Fab")
		)
		(fp_line
			(start 0.12065 -0.3048)
			(end 0.67945 -0.3048)
			(stroke
				(width 0.1)
				(type default)
			)
			(layer "F.Fab")
		)
		(fp_line
			(start 0.12065 -0.2794)
			(end 0.12065 -0.3048)
			(stroke
				(width 0.1)
				(type default)
			)
			(layer "F.Fab")
		)
		(fp_line
			(start 0.67945 -0.3048)
			(end 0.67945 0.3048)
			(stroke
				(width 0.1)
				(type default)
			)
			(layer "F.Fab")
		)
		(fp_line
			(start 0.67945 0.3048)
			(end 0.120396 0.3048)
			(stroke
				(width 0.1)
				(type default)
			)
			(layer "F.Fab")
		)
		(pad "1" smd circle
			(at -0.40005 0)
			(size 0 0)
			(layers "F.Cu" "F.Mask" "F.Paste")
			(net "P3V3_AUX")
		)
		(pad "2" smd circle
			(at 0.40005 0)
			(size 0 0)
			(layers "F.Cu" "F.Mask" "F.Paste")
			(net "GND")
		)
	)
	(footprint ""
		(layer "F.Cu")
		(at 387.62178 -356.244906 90)
		(property "Reference" "C761"
			(at 0 0 90)
			(layer "F.SilkS")
			(hide yes)
			(effects
				(font
					(size 1.27 1.27)
				)
			)
		)
		(property "Value" ""
			(at 0 0 90)
			(layer "F.Fab")
			(effects
				(font
					(size 1.27 1.27)
				)
			)
		)
		(duplicate_pad_numbers_are_jumpers no)
		(fp_line
			(start 0.299974 -0.150114)
			(end 0.299974 0.150114)
			(stroke
				(width 0.1)
				(type default)
			)
			(layer "F.Fab")
		)
		(fp_line
			(start -0.299974 -0.150114)
			(end 0.299974 -0.150114)
			(stroke
				(width 0.1)
				(type default)
			)
			(layer "F.Fab")
		)
		(fp_line
			(start 0.299974 0.150114)
			(end -0.299974 0.150114)
			(stroke
				(width 0.1)
				(type default)
			)
			(layer "F.Fab")
		)
		(fp_line
			(start -0.299974 0.150114)
			(end -0.299974 -0.150114)
			(stroke
				(width 0.1)
				(type default)
			)
			(layer "F.Fab")
		)
		(pad "1" smd rect
			(at -0.2667 0 90)
			(size 0.3048 0.381)
			(layers "F.Cu" "F.Mask" "F.Paste")
			(net "P5E_PEX3_STN5_TX_DN<80>")
		)
		(pad "2" smd rect
			(at 0.2667 0 90)
			(size 0.3048 0.381)
			(layers "F.Cu" "F.Mask" "F.Paste")
			(net "P5E_PEX3_STN5_TX_C_DN<80>")
		)
	)
	(footprint ""
		(layer "F.Cu")
		(at 420.096188 -47.20082 90)
		(property "Reference" "C404"
			(at 0 0 90)
			(layer "F.SilkS")
			(hide yes)
			(effects
				(font
					(size 1.27 1.27)
				)
			)
		)
		(property "Value" ""
			(at 0 0 90)
			(layer "F.Fab")
			(effects
				(font
					(size 1.27 1.27)
				)
			)
		)
		(duplicate_pad_numbers_are_jumpers no)
		(fp_line
			(start 0.7874 -0.4064)
			(end 0.7874 0.4064)
			(stroke
				(width 0.1524)
				(type default)
			)
			(layer "F.SilkS")
		)
		(fp_line
			(start -0.7874 -0.4064)
			(end 0.7874 -0.4064)
			(stroke
				(width 0.1524)
				(type default)
			)
			(layer "F.SilkS")
		)
		(fp_line
			(start 0.7874 0.4064)
			(end -0.7874 0.4064)
			(stroke
				(width 0.1524)
				(type default)
			)
			(layer "F.SilkS")
		)
		(fp_line
			(start -0.7874 0.4064)
			(end -0.7874 -0.4064)
			(stroke
				(width 0.1524)
				(type default)
			)
			(layer "F.SilkS")
		)
		(fp_line
			(start -0.12065 -0.305054)
			(end -0.12065 -0.2794)
			(stroke
				(width 0.1)
				(type default)
			)
			(layer "F.Fab")
		)
		(fp_line
			(start -0.67945 -0.305054)
			(end -0.12065 -0.305054)
			(stroke
				(width 0.1)
				(type default)
			)
			(layer "F.Fab")
		)
		(fp_line
			(start 0.67945 -0.3048)
			(end 0.67945 0.3048)
			(stroke
				(width 0.1)
				(type default)
			)
			(layer "F.Fab")
		)
		(fp_line
			(start 0.12065 -0.3048)
			(end 0.67945 -0.3048)
			(stroke
				(width 0.1)
				(type default)
			)
			(layer "F.Fab")
		)
		(fp_line
			(start 0.12065 -0.2794)
			(end 0.12065 -0.3048)
			(stroke
				(width 0.1)
				(type default)
			)
			(layer "F.Fab")
		)
		(fp_line
			(start -0.12065 -0.2794)
			(end 0.12065 -0.2794)
			(stroke
				(width 0.1)
				(type default)
			)
			(layer "F.Fab")
		)
		(fp_line
			(start 0.120396 0.2794)
			(end -0.12065 0.2794)
			(stroke
				(width 0.1)
				(type default)
			)
			(layer "F.Fab")
		)
		(fp_line
			(start -0.12065 0.2794)
			(end -0.12065 0.3048)
			(stroke
				(width 0.1)
				(type default)
			)
			(layer "F.Fab")
		)
		(fp_line
			(start 0.67945 0.3048)
			(end 0.120396 0.3048)
			(stroke
				(width 0.1)
				(type default)
			)
			(layer "F.Fab")
		)
		(fp_line
			(start 0.120396 0.3048)
			(end 0.120396 0.2794)
			(stroke
				(width 0.1)
				(type default)
			)
			(layer "F.Fab")
		)
		(fp_line
			(start -0.12065 0.3048)
			(end -0.67945 0.3048)
			(stroke
				(width 0.1)
				(type default)
			)
			(layer "F.Fab")
		)
		(fp_line
			(start -0.67945 0.3048)
			(end -0.67945 -0.305054)
			(stroke
				(width 0.1)
				(type default)
			)
			(layer "F.Fab")
		)
		(pad "1" smd circle
			(at -0.40005 0 90)
			(size 0 0)
			(layers "F.Cu" "F.Mask" "F.Paste")
			(net "P12V_SSD14_R")
		)
		(pad "2" smd circle
			(at 0.40005 0 90)
			(size 0 0)
			(layers "F.Cu" "F.Mask" "F.Paste")
			(net "GND")
		)
	)
)
